G04*
G04 #@! TF.GenerationSoftware,Altium Limited,Altium Designer,23.6.0 (18)*
G04*
G04 Layer_Color=16711935*
%FSLAX44Y44*%
%MOMM*%
G71*
G04*
G04 #@! TF.SameCoordinates,0D6CC9A4-690D-4EF8-AA6E-9FB67146BD04*
G04*
G04*
G04 #@! TF.FilePolarity,Negative*
G04*
G01*
G75*
%ADD47R,0.7200X0.6700*%
%ADD53R,1.0500X1.1000*%
%ADD54R,1.1000X1.0500*%
%ADD55R,0.7200X0.7000*%
%ADD57R,0.7000X0.7200*%
%ADD60C,2.0000*%
%ADD62R,2.1200X2.1200*%
%ADD63C,2.1200*%
%ADD64C,2.1900*%
%ADD65C,5.7000*%
%ADD66C,0.1000*%
%ADD67C,0.7000*%
%ADD92R,1.6000X0.5500*%
%ADD93R,1.6500X0.7000*%
%ADD94R,0.9500X0.4000*%
%ADD95R,1.7000X1.7000*%
%ADD96R,1.2000X0.4000*%
%ADD97R,0.9000X1.1000*%
%ADD98R,0.7000X0.6500*%
%ADD99C,6.3000*%
%ADD100R,0.6500X0.7000*%
D47*
X99000Y226250D02*
D03*
Y216650D02*
D03*
D53*
X374500Y389088D02*
D03*
X390500D02*
D03*
X331500Y412500D02*
D03*
X315500D02*
D03*
D54*
X200650Y174955D02*
D03*
Y190955D02*
D03*
X220624Y328550D02*
D03*
Y312550D02*
D03*
D55*
X193167D02*
D03*
Y321750D02*
D03*
X206778D02*
D03*
Y312550D02*
D03*
X184407Y191350D02*
D03*
Y182150D02*
D03*
X171518Y182500D02*
D03*
Y191700D02*
D03*
D57*
X113425Y358378D02*
D03*
X122625D02*
D03*
X306100Y349750D02*
D03*
X296900D02*
D03*
D60*
X16836Y491645D02*
D03*
X492909Y492701D02*
D03*
X492478Y15188D02*
D03*
D62*
X34250Y179000D02*
D03*
D63*
X59650D02*
D03*
D64*
X192000Y484000D02*
D03*
X51000Y457000D02*
D03*
X457000Y51000D02*
D03*
Y457000D02*
D03*
X132000Y484000D02*
D03*
X102000D02*
D03*
X72000D02*
D03*
X457000Y254000D02*
D03*
X51000Y51000D02*
D03*
X162000Y484000D02*
D03*
D65*
X465000Y138000D02*
D03*
Y349000D02*
D03*
D66*
X95000Y71000D02*
D03*
X406000Y41000D02*
D03*
X413000Y452000D02*
D03*
X95000Y437000D02*
D03*
D67*
X315000Y203311D02*
D03*
X241500Y478750D02*
D03*
X220968Y339000D02*
D03*
X349911Y39320D02*
D03*
X350161Y52070D02*
D03*
X350607Y63513D02*
D03*
X350161Y75070D02*
D03*
X360411Y74570D02*
D03*
X360857Y63014D02*
D03*
X360411Y51570D02*
D03*
X360161Y38820D02*
D03*
X350911Y90320D02*
D03*
X351161Y103070D02*
D03*
X351607Y114514D02*
D03*
X351161Y126070D02*
D03*
X361411Y125570D02*
D03*
X361857Y114014D02*
D03*
X361411Y102570D02*
D03*
X361161Y89820D02*
D03*
X308000Y46100D02*
D03*
X320750Y45850D02*
D03*
X332193Y45405D02*
D03*
X343750Y45850D02*
D03*
X343250Y35600D02*
D03*
X331693Y35155D02*
D03*
X320250Y35600D02*
D03*
X307500Y35850D02*
D03*
Y84500D02*
D03*
X320250Y84250D02*
D03*
X331693Y83804D02*
D03*
X343250Y84250D02*
D03*
X342750Y74000D02*
D03*
X331194Y73554D02*
D03*
X319750Y74000D02*
D03*
X307000Y74250D02*
D03*
X306320Y53339D02*
D03*
X319070Y53089D02*
D03*
X330513Y52643D02*
D03*
X342070Y53089D02*
D03*
X342570Y63339D02*
D03*
X331013Y62893D02*
D03*
X319570Y63339D02*
D03*
X306820Y63589D02*
D03*
Y105339D02*
D03*
X319570Y105089D02*
D03*
X331013Y104643D02*
D03*
X342570Y105089D02*
D03*
X342070Y94839D02*
D03*
X330513Y94393D02*
D03*
X319070Y94839D02*
D03*
X306320Y95089D02*
D03*
X307000Y116000D02*
D03*
X319750Y115750D02*
D03*
X331194Y115304D02*
D03*
X342750Y115750D02*
D03*
X343250Y126000D02*
D03*
X331693Y125554D02*
D03*
X320250Y126000D02*
D03*
X307500Y126250D02*
D03*
X192905Y69250D02*
D03*
X183138Y69052D02*
D03*
X173250Y65020D02*
D03*
X161750Y64750D02*
D03*
X149500Y63250D02*
D03*
X234398Y422690D02*
D03*
X223373Y415288D02*
D03*
X298715Y489190D02*
D03*
X351500Y488750D02*
D03*
D92*
X64618Y390689D02*
D03*
X122618D02*
D03*
Y377689D02*
D03*
X64618Y371189D02*
D03*
Y377689D02*
D03*
Y384189D02*
D03*
X122618D02*
D03*
Y371189D02*
D03*
D93*
X171500Y215250D02*
D03*
Y240650D02*
D03*
X117500D02*
D03*
Y227950D02*
D03*
Y215250D02*
D03*
X171500Y227950D02*
D03*
Y253350D02*
D03*
X117500D02*
D03*
X171250Y274450D02*
D03*
X117250D02*
D03*
Y299850D02*
D03*
X171250Y312550D02*
D03*
Y299850D02*
D03*
Y287150D02*
D03*
X117250D02*
D03*
Y312550D02*
D03*
D94*
X276914Y360775D02*
D03*
Y365775D02*
D03*
Y370775D02*
D03*
Y375775D02*
D03*
X305914Y370775D02*
D03*
Y375775D02*
D03*
Y365775D02*
D03*
Y360775D02*
D03*
D95*
X291414Y368275D02*
D03*
D96*
X71500Y266500D02*
D03*
Y261500D02*
D03*
Y256500D02*
D03*
Y251500D02*
D03*
Y231500D02*
D03*
Y236500D02*
D03*
Y241500D02*
D03*
Y246500D02*
D03*
Y276500D02*
D03*
Y271500D02*
D03*
X36500D02*
D03*
Y276500D02*
D03*
Y246500D02*
D03*
Y241500D02*
D03*
Y236500D02*
D03*
Y231500D02*
D03*
Y251500D02*
D03*
Y256500D02*
D03*
Y261500D02*
D03*
Y266500D02*
D03*
D97*
X279500Y339500D02*
D03*
X264500D02*
D03*
X122500Y343710D02*
D03*
X107500D02*
D03*
D98*
X421000Y193594D02*
D03*
X412500D02*
D03*
X279005Y198941D02*
D03*
X270505D02*
D03*
X224129Y199191D02*
D03*
X232629D02*
D03*
X27250Y357460D02*
D03*
X35750D02*
D03*
X27250Y367710D02*
D03*
X35750D02*
D03*
X27285Y397960D02*
D03*
X35785D02*
D03*
X35750Y347460D02*
D03*
X27250D02*
D03*
X35750Y377710D02*
D03*
X27250D02*
D03*
X35750Y387710D02*
D03*
X27250D02*
D03*
X334750Y343750D02*
D03*
X326250D02*
D03*
X334750Y354236D02*
D03*
X326250D02*
D03*
Y334250D02*
D03*
X334750D02*
D03*
X326000Y363750D02*
D03*
X334500D02*
D03*
X394750Y274431D02*
D03*
X386250D02*
D03*
D99*
X95000Y71000D02*
D03*
X406000Y41000D02*
D03*
X413000Y452000D02*
D03*
X95000Y437000D02*
D03*
D100*
X243755Y190711D02*
D03*
Y199211D02*
D03*
X258755Y190441D02*
D03*
Y198941D02*
D03*
X338500Y382750D02*
D03*
Y374250D02*
D03*
X327500Y374500D02*
D03*
Y383000D02*
D03*
X394750Y284000D02*
D03*
Y292500D02*
D03*
X403000Y202094D02*
D03*
Y193594D02*
D03*
M02*
